# T6G (Grand Teton) — schematic netlist excerpt (pin names and nets, part order shuffled) for the footprints in the layout excerpt that follows; sources: Cadence DE-HDL packaged netlist, KiCad conversion of 04192023_DAF0TMB3IC0_F0TG_MB_C_brd_V02_OCP.brd

C6057  Q_CAP  0.01UF 50V 10% X7R  pkg C0402  page 177 : A = P1V2_AUX ; B = GND
C2644  Q_CAP  22UF 4V 20% X6S  pkg C0402  page 70 : A = PVDDIO_P0 ; B = GND

(kicad_pcb
	(version 20260206)
	(generator "pcbnew")
	(generator_version "10.0")
	(general
		(thickness 1.6)
		(legacy_teardrops no)
	)
	(paper "A4")
	(title_block
		(title "04192023_DAF0TMB3IC0_F0TG_MB_C_brd_V02_OCP.brd")
		(comment 1 "Grand Teton / footprints 5505-5506 of 8354")
	)
	(layers
		(0 "F.Cu" signal "TOP")
		(4 "In1.Cu" signal "GND")
		(6 "In2.Cu" signal "IN1")
		(8 "In3.Cu" signal "GND1")
		(10 "In4.Cu" signal "IN2")
		(12 "In5.Cu" signal "GND2")
		(14 "In6.Cu" signal "IN3")
		(16 "In7.Cu" signal "GND3")
		(18 "In8.Cu" signal "VCC")
		(20 "In9.Cu" signal "VCC1")
		(22 "In10.Cu" signal "GND4")
		(24 "In11.Cu" signal "IN4")
		(26 "In12.Cu" signal "GND5")
		(28 "In13.Cu" signal "IN5")
		(30 "In14.Cu" signal "GND6")
		(32 "In15.Cu" signal "IN6")
		(34 "In16.Cu" signal "GND7")
		(2 "B.Cu" signal "BOTTOM")
		(9 "F.Adhes" user "F.Adhesive")
		(11 "B.Adhes" user "B.Adhesive")
		(13 "F.Paste" user "Package Geometry/Pastemask Top")
		(15 "B.Paste" user "Package Geometry/Pastemask Bottom")
		(5 "F.SilkS" user "Ref Des/Silkscreen Top")
		(7 "B.SilkS" user "Ref Des/Silkscreen Bottom")
		(1 "F.Mask" user "Board Geometry/Soldermask Top")
		(3 "B.Mask" user "Board Geometry/Soldermask Bottom")
		(17 "Dwgs.User" user "User.Drawings")
		(19 "Cmts.User" user "User.Comments")
		(21 "Eco1.User" user "User.Eco1")
		(23 "Eco2.User" user "User.Eco2")
		(25 "Edge.Cuts" user "Board Geometry/Outline")
		(27 "Margin" user)
		(31 "F.CrtYd" user "Package Geometry/Place Bound Top")
		(29 "B.CrtYd" user "Package Geometry/Place Bound Bottom")
		(35 "F.Fab" user "Ref Des/Assembly Top")
		(33 "B.Fab" user "Ref Des/Assembly Bottom")
	)
	(footprint ""
		(layer "B.Cu")
		(at 138.65352 -36.701222 180)
		(property "Reference" "C6057"
			(at 0 0 0)
			(layer "B.SilkS")
			(hide yes)
			(effects
				(font
					(size 1.27 1.27)
				)
				(justify mirror)
			)
		)
		(property "Value" ""
			(at 0 0 0)
			(layer "B.Fab")
			(effects
				(font
					(size 1.27 1.27)
				)
				(justify mirror)
			)
		)
		(duplicate_pad_numbers_are_jumpers no)
		(fp_line
			(start 0.7874 0.4064)
			(end 0.7874 -0.4064)
			(stroke
				(width 0.1524)
				(type default)
			)
			(layer "B.SilkS")
		)
		(fp_line
			(start 0.7874 -0.4064)
			(end -0.7874 -0.4064)
			(stroke
				(width 0.1524)
				(type default)
			)
			(layer "B.SilkS")
		)
		(fp_line
			(start -0.7874 0.4064)
			(end 0.7874 0.4064)
			(stroke
				(width 0.1524)
				(type default)
			)
			(layer "B.SilkS")
		)
		(fp_line
			(start -0.7874 -0.4064)
			(end -0.7874 0.4064)
			(stroke
				(width 0.1524)
				(type default)
			)
			(layer "B.SilkS")
		)
		(fp_line
			(start 0.67945 0.3048)
			(end 0.67945 -0.305054)
			(stroke
				(width 0.1)
				(type default)
			)
			(layer "B.Fab")
		)
		(fp_line
			(start 0.67945 -0.305054)
			(end 0.12065 -0.305054)
			(stroke
				(width 0.1)
				(type default)
			)
			(layer "B.Fab")
		)
		(fp_line
			(start 0.12065 0.3048)
			(end 0.67945 0.3048)
			(stroke
				(width 0.1)
				(type default)
			)
			(layer "B.Fab")
		)
		(fp_line
			(start 0.12065 0.2794)
			(end 0.12065 0.3048)
			(stroke
				(width 0.1)
				(type default)
			)
			(layer "B.Fab")
		)
		(fp_line
			(start 0.12065 -0.2794)
			(end -0.12065 -0.2794)
			(stroke
				(width 0.1)
				(type default)
			)
			(layer "B.Fab")
		)
		(fp_line
			(start 0.12065 -0.305054)
			(end 0.12065 -0.2794)
			(stroke
				(width 0.1)
				(type default)
			)
			(layer "B.Fab")
		)
		(fp_line
			(start -0.120396 0.3048)
			(end -0.120396 0.2794)
			(stroke
				(width 0.1)
				(type default)
			)
			(layer "B.Fab")
		)
		(fp_line
			(start -0.120396 0.2794)
			(end 0.12065 0.2794)
			(stroke
				(width 0.1)
				(type default)
			)
			(layer "B.Fab")
		)
		(fp_line
			(start -0.12065 -0.2794)
			(end -0.12065 -0.3048)
			(stroke
				(width 0.1)
				(type default)
			)
			(layer "B.Fab")
		)
		(fp_line
			(start -0.12065 -0.3048)
			(end -0.67945 -0.3048)
			(stroke
				(width 0.1)
				(type default)
			)
			(layer "B.Fab")
		)
		(fp_line
			(start -0.67945 0.3048)
			(end -0.120396 0.3048)
			(stroke
				(width 0.1)
				(type default)
			)
			(layer "B.Fab")
		)
		(fp_line
			(start -0.67945 -0.3048)
			(end -0.67945 0.3048)
			(stroke
				(width 0.1)
				(type default)
			)
			(layer "B.Fab")
		)
		(pad "1" smd circle
			(at 0.40005 0)
			(size 0 0)
			(layers "B.Cu" "B.Mask" "B.Paste")
			(net "P1V2_AUX")
		)
		(pad "2" smd circle
			(at -0.40005 0)
			(size 0 0)
			(layers "B.Cu" "B.Mask" "B.Paste")
			(net "GND")
		)
	)
	(footprint ""
		(layer "B.Cu")
		(at 353.900232 -257.455162 180)
		(property "Reference" "C2644"
			(at 0 0 0)
			(layer "B.SilkS")
			(hide yes)
			(effects
				(font
					(size 1.27 1.27)
				)
				(justify mirror)
			)
		)
		(property "Value" ""
			(at 0 0 0)
			(layer "B.Fab")
			(effects
				(font
					(size 1.27 1.27)
				)
				(justify mirror)
			)
		)
		(duplicate_pad_numbers_are_jumpers no)
		(fp_line
			(start 0.7874 0.4064)
			(end 0.7874 -0.4064)
			(stroke
				(width 0.1524)
				(type default)
			)
			(layer "B.SilkS")
		)
		(fp_line
			(start 0.7874 -0.4064)
			(end -0.7874 -0.4064)
			(stroke
				(width 0.1524)
				(type default)
			)
			(layer "B.SilkS")
		)
		(fp_line
			(start -0.7874 0.4064)
			(end 0.7874 0.4064)
			(stroke
				(width 0.1524)
				(type default)
			)
			(layer "B.SilkS")
		)
		(fp_line
			(start -0.7874 -0.4064)
			(end -0.7874 0.4064)
			(stroke
				(width 0.1524)
				(type default)
			)
			(layer "B.SilkS")
		)
		(fp_line
			(start 0.67945 0.3048)
			(end 0.67945 -0.305054)
			(stroke
				(width 0.1)
				(type default)
			)
			(layer "B.Fab")
		)
		(fp_line
			(start 0.67945 -0.305054)
			(end 0.12065 -0.305054)
			(stroke
				(width 0.1)
				(type default)
			)
			(layer "B.Fab")
		)
		(fp_line
			(start 0.12065 0.3048)
			(end 0.67945 0.3048)
			(stroke
				(width 0.1)
				(type default)
			)
			(layer "B.Fab")
		)
		(fp_line
			(start 0.12065 0.2794)
			(end 0.12065 0.3048)
			(stroke
				(width 0.1)
				(type default)
			)
			(layer "B.Fab")
		)
		(fp_line
			(start 0.12065 -0.2794)
			(end -0.12065 -0.2794)
			(stroke
				(width 0.1)
				(type default)
			)
			(layer "B.Fab")
		)
		(fp_line
			(start 0.12065 -0.305054)
			(end 0.12065 -0.2794)
			(stroke
				(width 0.1)
				(type default)
			)
			(layer "B.Fab")
		)
		(fp_line
			(start -0.120396 0.3048)
			(end -0.120396 0.2794)
			(stroke
				(width 0.1)
				(type default)
			)
			(layer "B.Fab")
		)
		(fp_line
			(start -0.120396 0.2794)
			(end 0.12065 0.2794)
			(stroke
				(width 0.1)
				(type default)
			)
			(layer "B.Fab")
		)
		(fp_line
			(start -0.12065 -0.2794)
			(end -0.12065 -0.3048)
			(stroke
				(width 0.1)
				(type default)
			)
			(layer "B.Fab")
		)
		(fp_line
			(start -0.12065 -0.3048)
			(end -0.67945 -0.3048)
			(stroke
				(width 0.1)
				(type default)
			)
			(layer "B.Fab")
		)
		(fp_line
			(start -0.67945 0.3048)
			(end -0.120396 0.3048)
			(stroke
				(width 0.1)
				(type default)
			)
			(layer "B.Fab")
		)
		(fp_line
			(start -0.67945 -0.3048)
			(end -0.67945 0.3048)
			(stroke
				(width 0.1)
				(type default)
			)
			(layer "B.Fab")
		)
		(pad "1" smd circle
			(at 0.40005 0)
			(size 0 0)
			(layers "B.Cu" "B.Mask" "B.Paste")
			(net "PVDDIO_P0")
		)
		(pad "2" smd circle
			(at -0.40005 0)
			(size 0 0)
			(layers "B.Cu" "B.Mask" "B.Paste")
			(net "GND")
		)
	)
)
